# BASEBOARD_FAB2 (Tioga Pass) — schematic netlist excerpt (pin names and nets, part order shuffled) for the footprints in the layout excerpt that follows; sources: Cadence DE-HDL packaged netlist, KiCad conversion of Wiwynn_Tioga_Pass_MB.brd

C7P9  CAP  100UF 4V 20% X5R  pkg 0805  page 76 : A = PVCCMCP_CPU1 ; B = GND
FB2M2  FERRITE  120 FB  pkg SM  page 127 : A = P1V05_PCH_STBY ; B = P1V05_PCH_STBY_WM26_PLL
R1W36  RES  4.75K 1% CHIP  pkg 0402  page 176 : A = P3V3_STBY ; B = SMB_DEBUG_STBY_LVC3_SCL_CONN

(kicad_pcb
	(version 20260206)
	(generator "pcbnew")
	(generator_version "10.0")
	(general
		(thickness 1.6)
		(legacy_teardrops no)
	)
	(paper "A4")
	(title_block
		(title "Wiwynn_Tioga_Pass_MB.brd")
		(comment 1 "Tioga Pass / footprints 2440-2442 of 4770")
	)
	(layers
		(0 "F.Cu" signal "TOP")
		(4 "In1.Cu" signal "L2GND")
		(6 "In2.Cu" signal "L3")
		(8 "In3.Cu" signal "L4GND")
		(10 "In4.Cu" signal "L5")
		(12 "In5.Cu" signal "L6GND")
		(14 "In6.Cu" signal "L7VCC")
		(16 "In7.Cu" signal "L8VCC")
		(18 "In8.Cu" signal "L9GND")
		(20 "In9.Cu" signal "L10")
		(22 "In10.Cu" signal "L11GND")
		(24 "In11.Cu" signal "L12")
		(26 "In12.Cu" signal "L13GND")
		(2 "B.Cu" signal "BOTTOM")
		(9 "F.Adhes" user "F.Adhesive")
		(11 "B.Adhes" user "B.Adhesive")
		(13 "F.Paste" user "Package Geometry/Pastemask Top")
		(15 "B.Paste" user "Package Geometry/Pastemask Bottom")
		(5 "F.SilkS" user "Ref Des/Silkscreen Top")
		(7 "B.SilkS" user "Ref Des/Silkscreen Bottom")
		(1 "F.Mask" user "Board Geometry/Soldermask Top")
		(3 "B.Mask" user "Board Geometry/Soldermask Bottom")
		(17 "Dwgs.User" user "User.Drawings")
		(19 "Cmts.User" user "User.Comments")
		(21 "Eco1.User" user "User.Eco1")
		(23 "Eco2.User" user "User.Eco2")
		(25 "Edge.Cuts" user "Board Geometry/Outline")
		(27 "Margin" user)
		(31 "F.CrtYd" user "Package Geometry/Place Bound Top")
		(29 "B.CrtYd" user "Package Geometry/Place Bound Bottom")
		(35 "F.Fab" user "Ref Des/Assembly Top")
		(33 "B.Fab" user "Ref Des/Assembly Bottom")
	)
	(footprint ""
		(layer "B.Cu")
		(at 110.007654 -77.82814)
		(property "Reference" "C7P9"
			(at 0 0 0)
			(layer "B.SilkS")
			(hide yes)
			(effects
				(font
					(size 1.27 1.27)
				)
				(justify mirror)
			)
		)
		(property "Value" ""
			(at 0 0 0)
			(layer "B.Fab")
			(effects
				(font
					(size 1.27 1.27)
				)
				(justify mirror)
			)
		)
		(duplicate_pad_numbers_are_jumpers no)
		(fp_poly
			(pts
				(xy 0.7239 -0.2159) (xy -0.7239 -0.2159) (xy -0.7239 1.9939) (xy 0.7239 1.9939)
			)
			(stroke
				(width 0)
				(type default)
			)
			(fill no)
			(layer "B.CrtYd")
		)
		(fp_line
			(start -0.7239 -0.2159)
			(end 0.7239 -0.2159)
			(stroke
				(width 0.1)
				(type default)
			)
			(layer "B.Fab")
		)
		(fp_line
			(start -0.7239 1.9939)
			(end -0.7239 -0.2159)
			(stroke
				(width 0.1)
				(type default)
			)
			(layer "B.Fab")
		)
		(fp_line
			(start 0.7239 -0.2159)
			(end 0.7239 1.9939)
			(stroke
				(width 0.1)
				(type default)
			)
			(layer "B.Fab")
		)
		(fp_line
			(start 0.7239 1.9939)
			(end -0.7239 1.9939)
			(stroke
				(width 0.1)
				(type default)
			)
			(layer "B.Fab")
		)
		(pad "1" smd rect
			(at 0 0 180)
			(size 1.27 1.016)
			(layers "B.Cu" "B.Mask" "B.Paste")
			(net "PVCCMCP_CPU1")
		)
		(pad "2" smd rect
			(at 0 1.778 180)
			(size 1.27 1.016)
			(layers "B.Cu" "B.Mask" "B.Paste")
			(net "GND")
		)
		(zone
			(layer "B.Cu")
			(hatch none 0.5)
			(connect_pads
				(clearance 0)
			)
			(min_thickness 0.25)
			(keepout
				(tracks not_allowed)
				(vias allowed)
				(pads allowed)
				(copperpour not_allowed)
				(footprints allowed)
			)
			(placement
				(enabled no)
				(sheetname "")
			)
			(fill
				(thermal_gap 0.5)
				(thermal_bridge_width 0.5)
				(island_removal_mode 0)
			)
			(polygon
				(pts
					(xy 110.642654 -77.32014) (xy 109.372654 -77.32014) (xy 109.372654 -76.55814) (xy 110.642654 -76.55814)
				)
			)
		)
	)
	(footprint ""
		(layer "B.Cu")
		(at 408.1272 -122.0216 90)
		(property "Reference" "FB2M2"
			(at 0 0 90)
			(layer "B.SilkS")
			(hide yes)
			(effects
				(font
					(size 1.27 1.27)
				)
				(justify mirror)
			)
		)
		(property "Value" ""
			(at 0 0 90)
			(layer "B.Fab")
			(effects
				(font
					(size 1.27 1.27)
				)
				(justify mirror)
			)
		)
		(duplicate_pad_numbers_are_jumpers no)
		(fp_poly
			(pts
				(xy 0.15113 -0.47498) (xy -1.59893 -0.47498) (xy -1.59893 0.47498) (xy 0.15113 0.47498)
			)
			(stroke
				(width 0)
				(type default)
			)
			(fill no)
			(layer "B.CrtYd")
		)
		(fp_line
			(start 0.15113 -0.47498)
			(end -1.59893 -0.47498)
			(stroke
				(width 0.1)
				(type default)
			)
			(layer "B.Fab")
		)
		(fp_line
			(start -1.59893 -0.47498)
			(end -1.59893 0.47498)
			(stroke
				(width 0.1)
				(type default)
			)
			(layer "B.Fab")
		)
		(fp_line
			(start 0.15113 0.47498)
			(end 0.15113 -0.47498)
			(stroke
				(width 0.1)
				(type default)
			)
			(layer "B.Fab")
		)
		(fp_line
			(start -1.59893 0.47498)
			(end 0.15113 0.47498)
			(stroke
				(width 0.1)
				(type default)
			)
			(layer "B.Fab")
		)
		(pad "1" smd rect
			(at 0 0 270)
			(size 0.9398 0.9398)
			(layers "B.Cu" "B.Mask" "B.Paste")
			(net "P1V05_PCH_STBY")
		)
		(pad "2" smd rect
			(at -1.4478 0 270)
			(size 0.9398 0.9398)
			(layers "B.Cu" "B.Mask" "B.Paste")
			(net "P1V05_PCH_STBY_WM26_PLL")
		)
		(zone
			(layer "B.Cu")
			(hatch none 0.5)
			(connect_pads
				(clearance 0)
			)
			(min_thickness 0.25)
			(keepout
				(tracks not_allowed)
				(vias allowed)
				(pads allowed)
				(copperpour not_allowed)
				(footprints allowed)
			)
			(placement
				(enabled no)
				(sheetname "")
			)
			(fill
				(thermal_gap 0.5)
				(thermal_bridge_width 0.5)
				(island_removal_mode 0)
			)
			(polygon
				(pts
					(xy 408.5971 -121.5517) (xy 407.6573 -121.5517) (xy 407.6573 -121.0437) (xy 408.5971 -121.0437)
				)
			)
		)
		(zone
			(layer "B.Cu")
			(hatch none 0.5)
			(connect_pads
				(clearance 0)
			)
			(min_thickness 0.25)
			(keepout
				(tracks allowed)
				(vias not_allowed)
				(pads allowed)
				(copperpour not_allowed)
				(footprints allowed)
			)
			(placement
				(enabled no)
				(sheetname "")
			)
			(fill
				(thermal_gap 0.5)
				(thermal_bridge_width 0.5)
				(island_removal_mode 0)
			)
			(polygon
				(pts
					(xy 408.5971 -121.5517) (xy 407.6573 -121.5517) (xy 407.6573 -121.0437) (xy 408.5971 -121.0437)
				)
			)
		)
	)
	(footprint ""
		(layer "B.Cu")
		(at 473.91574 -135.41756 90)
		(property "Reference" "R1W36"
			(at 0.8382 -0.67818 90)
			(unlocked yes)
			(layer "B.SilkS")
			(effects
				(font
					(size 0.4064 0.254)
					(thickness 0.1524)
				)
				(justify left mirror)
			)
		)
		(property "Value" ""
			(at 0 0 90)
			(layer "B.Fab")
			(effects
				(font
					(size 1.27 1.27)
				)
				(justify mirror)
			)
		)
		(duplicate_pad_numbers_are_jumpers no)
		(fp_poly
			(pts
				(xy 0.2794 -0.1016) (xy -0.2794 -0.1016) (xy -0.2794 0.9906) (xy 0.2794 0.9906)
			)
			(stroke
				(width 0)
				(type default)
			)
			(fill no)
			(layer "B.CrtYd")
		)
		(fp_line
			(start 0.2794 -0.1016)
			(end 0.2794 0.9906)
			(stroke
				(width 0.1)
				(type default)
			)
			(layer "B.Fab")
		)
		(fp_line
			(start -0.2794 -0.1016)
			(end 0.2794 -0.1016)
			(stroke
				(width 0.1)
				(type default)
			)
			(layer "B.Fab")
		)
		(fp_line
			(start 0.2794 0.9906)
			(end -0.2794 0.9906)
			(stroke
				(width 0.1)
				(type default)
			)
			(layer "B.Fab")
		)
		(fp_line
			(start -0.2794 0.9906)
			(end -0.2794 -0.1016)
			(stroke
				(width 0.1)
				(type default)
			)
			(layer "B.Fab")
		)
		(pad "1" smd rect
			(at 0 0 270)
			(size 0.508 0.508)
			(layers "B.Cu" "B.Mask" "B.Paste")
			(net "P3V3_STBY")
		)
		(pad "2" smd rect
			(at 0 0.889 270)
			(size 0.508 0.508)
			(layers "B.Cu" "B.Mask" "B.Paste")
			(net "SMB_DEBUG_STBY_LVC3_SCL_CONN")
		)
		(zone
			(layer "B.Cu")
			(hatch none 0.5)
			(connect_pads
				(clearance 0)
			)
			(min_thickness 0.25)
			(keepout
				(tracks allowed)
				(vias not_allowed)
				(pads allowed)
				(copperpour not_allowed)
				(footprints allowed)
			)
			(placement
				(enabled no)
				(sheetname "")
			)
			(fill
				(thermal_gap 0.5)
				(thermal_bridge_width 0.5)
				(island_removal_mode 0)
			)
			(polygon
				(pts
					(xy 474.16974 -135.67156) (xy 474.16974 -135.16356) (xy 474.55074 -135.16356) (xy 474.55074 -135.67156)
				)
			)
		)
		(zone
			(layer "B.Cu")
			(hatch none 0.5)
			(connect_pads
				(clearance 0)
			)
			(min_thickness 0.25)
			(keepout
				(tracks not_allowed)
				(vias allowed)
				(pads allowed)
				(copperpour not_allowed)
				(footprints allowed)
			)
			(placement
				(enabled no)
				(sheetname "")
			)
			(fill
				(thermal_gap 0.5)
				(thermal_bridge_width 0.5)
				(island_removal_mode 0)
			)
			(polygon
				(pts
					(xy 474.55074 -135.67156) (xy 474.55074 -135.16356) (xy 474.16974 -135.16356) (xy 474.16974 -135.67156)
				)
			)
		)
	)
)
